(kicad_pcb
	(version 20260206)
	(generator "pcbnew")
	(generator_version "10.0")
	(general
		(thickness 1.6)
		(legacy_teardrops no)
	)
	(paper "A4")
	(title_block
		(title "dpb — 14545-sa.0730WZS0815.brd")
		(comment 1 "Honey Badger (Wiwynn) / footprints 483-489 of 1066")
	)
	(layers
		(0 "F.Cu" signal "TOP")
		(4 "In1.Cu" signal "L2GND")
		(6 "In2.Cu" signal "L3")
		(8 "In3.Cu" signal "L4VCC")
		(10 "In4.Cu" signal "L5VCC")
		(12 "In5.Cu" signal "L6")
		(14 "In6.Cu" signal "L7GND")
		(2 "B.Cu" signal "BOTTOM")
		(9 "F.Adhes" user "F.Adhesive")
		(11 "B.Adhes" user "B.Adhesive")
		(13 "F.Paste" user "Package Geometry/Pastemask Top")
		(15 "B.Paste" user "Package Geometry/Pastemask Bottom")
		(5 "F.SilkS" user "Ref Des/Silkscreen Top")
		(7 "B.SilkS" user "Ref Des/Silkscreen Bottom")
		(1 "F.Mask" user "Board Geometry/Soldermask Top")
		(3 "B.Mask" user "Board Geometry/Soldermask Bottom")
		(17 "Dwgs.User" user "User.Drawings")
		(19 "Cmts.User" user "User.Comments")
		(21 "Eco1.User" user "User.Eco1")
		(23 "Eco2.User" user "User.Eco2")
		(25 "Edge.Cuts" user "Board Geometry/Outline")
		(27 "Margin" user)
		(31 "F.CrtYd" user "Package Geometry/Place Bound Top")
		(29 "B.CrtYd" user "Package Geometry/Place Bound Bottom")
		(35 "F.Fab" user "Ref Des/Assembly Top")
		(33 "B.Fab" user "Ref Des/Assembly Bottom")
	)
	(footprint ""
		(layer "F.Cu")
		(at 77.342746 -19.586702 90)
		(property "Reference" "R302"
			(at 0 0 90)
			(layer "F.SilkS")
			(hide yes)
			(effects
				(font
					(size 1.27 1.27)
				)
			)
		)
		(property "Value" "2R2010J-1-GP"
			(at 0.254 -8.0772 90)
			(unlocked yes)
			(layer "F.Fab")
			(hide yes)
			(effects
				(font
					(size 1.016 1.016)
					(thickness 0.1524)
				)
			)
		)
		(property "Device Type" "R2010H28"
			(at 0.254 -9.6774 90)
			(unlocked yes)
			(layer "F.Fab")
			(hide yes)
			(effects
				(font
					(size 1.016 1.016)
					(thickness 0.1524)
				)
			)
		)
		(duplicate_pad_numbers_are_jumpers no)
		(fp_line
			(start 1.651 -3.302)
			(end -1.651 -3.302)
			(stroke
				(width 0.1524)
				(type default)
			)
			(layer "F.SilkS")
		)
		(fp_line
			(start -1.651 -3.302)
			(end -1.651 3.302)
			(stroke
				(width 0.1524)
				(type default)
			)
			(layer "F.SilkS")
		)
		(fp_line
			(start 1.651 3.302)
			(end 1.651 -3.302)
			(stroke
				(width 0.1524)
				(type default)
			)
			(layer "F.SilkS")
		)
		(fp_line
			(start -1.651 3.302)
			(end 1.651 3.302)
			(stroke
				(width 0.1524)
				(type default)
			)
			(layer "F.SilkS")
		)
		(fp_rect
			(start -1.7272 -3.3782)
			(end 1.7272 3.3782)
			(stroke
				(width 0)
				(type default)
			)
			(fill no)
			(layer "F.CrtYd")
		)
		(fp_poly
			(pts
				(xy 1.7272 3.3782) (xy 1.7272 -3.3782) (xy -1.7272 -3.3782) (xy -1.7272 3.3782)
			)
			(stroke
				(width 0)
				(type default)
			)
			(fill no)
			(layer "F.Fab")
		)
		(pad "1" smd rect
			(at 0 -2.3495 90)
			(size 2.794 1.143)
			(layers "F.Cu" "F.Mask" "F.Paste")
			(net "5V_PRE_14")
		)
		(pad "2" smd rect
			(at 0 2.3495 90)
			(size 2.794 1.143)
			(layers "F.Cu" "F.Mask" "F.Paste")
			(net "P5V_HDD14")
		)
	)
	(footprint ""
		(layer "F.Cu")
		(at 26.415746 -373.4562 180)
		(property "Reference" "R311"
			(at 0 0 180)
			(layer "F.SilkS")
			(hide yes)
			(effects
				(font
					(size 1.27 1.27)
				)
			)
		)
		(property "Value" "4K7R2J-2-GP"
			(at 0.064008 -3.993896 180)
			(unlocked yes)
			(layer "F.Fab")
			(hide yes)
			(effects
				(font
					(size 1.016 1.016)
					(thickness 0.1524)
				)
			)
		)
		(property "Device Type" "R402H16"
			(at 0.064008 -5.517896 180)
			(unlocked yes)
			(layer "F.Fab")
			(hide yes)
			(effects
				(font
					(size 1.016 1.016)
					(thickness 0.1524)
				)
			)
		)
		(duplicate_pad_numbers_are_jumpers no)
		(fp_line
			(start 0.508 -0.9398)
			(end -0.508 -0.9398)
			(stroke
				(width 0.1524)
				(type default)
			)
			(layer "F.SilkS")
		)
		(fp_line
			(start -0.508 -0.9398)
			(end -0.508 0.9398)
			(stroke
				(width 0.1524)
				(type default)
			)
			(layer "F.SilkS")
		)
		(fp_rect
			(start -0.508 0.9398)
			(end 0.508 -0.9398)
			(stroke
				(width 0)
				(type default)
			)
			(fill no)
			(layer "F.CrtYd")
		)
		(fp_rect
			(start -0.508 0.9398)
			(end 0.508 -0.9398)
			(stroke
				(width 0)
				(type default)
			)
			(fill no)
			(layer "F.Fab")
		)
		(pad "1" smd custom
			(at 0 -0.4445 180)
			(size 0.1397 0.1397)
			(layers "F.Cu" "F.Mask" "F.Paste")
			(net "P3V3")
			(options
				(clearance outline)
				(anchor circle)
			)
			(primitives
				(gr_poly
					(pts
						(arc
							(start -0.1778 -0.2794)
							(mid -0.249642 -0.249642)
							(end -0.2794 -0.1778)
						)
						(arc
							(start -0.2794 0.1778)
							(mid -0.249642 0.249642)
							(end -0.1778 0.2794)
						)
						(arc
							(start 0.1778 0.2794)
							(mid 0.249642 0.249642)
							(end 0.2794 0.1778)
						)
						(arc
							(start 0.2794 -0.1778)
							(mid 0.249642 -0.249642)
							(end 0.1778 -0.2794)
						)
					)
					(width 0)
					(fill yes)
				)
			)
		)
		(pad "2" smd custom
			(at 0 0.4445 180)
			(size 0.1397 0.1397)
			(layers "F.Cu" "F.Mask" "F.Paste")
			(net "I2C_B_TMP1_A2")
			(options
				(clearance outline)
				(anchor circle)
			)
			(primitives
				(gr_poly
					(pts
						(arc
							(start -0.1778 -0.2794)
							(mid -0.249642 -0.249642)
							(end -0.2794 -0.1778)
						)
						(arc
							(start -0.2794 0.1778)
							(mid -0.249642 0.249642)
							(end -0.1778 0.2794)
						)
						(arc
							(start 0.1778 0.2794)
							(mid 0.249642 0.249642)
							(end 0.2794 0.1778)
						)
						(arc
							(start 0.2794 -0.1778)
							(mid 0.249642 -0.249642)
							(end 0.1778 -0.2794)
						)
					)
					(width 0)
					(fill yes)
				)
			)
		)
	)
	(footprint ""
		(layer "F.Cu")
		(at 42.290746 -233.454702 180)
		(property "Reference" "R279"
			(at 0 0 180)
			(layer "F.SilkS")
			(hide yes)
			(effects
				(font
					(size 1.27 1.27)
				)
			)
		)
		(property "Value" "220R3F-1-GP"
			(at -0.0254 -2.5146 180)
			(unlocked yes)
			(layer "F.Fab")
			(hide yes)
			(effects
				(font
					(size 1.016 1.016)
					(thickness 0.1524)
				)
			)
		)
		(property "Device Type" "R603H22"
			(at -0.0254 -4.0386 180)
			(unlocked yes)
			(layer "F.Fab")
			(hide yes)
			(effects
				(font
					(size 1.016 1.016)
					(thickness 0.1524)
				)
			)
		)
		(duplicate_pad_numbers_are_jumpers no)
		(fp_line
			(start 0.2032 0)
			(end 0.4826 0)
			(stroke
				(width 0.2032)
				(type default)
			)
			(layer "F.SilkS")
		)
		(fp_line
			(start -0.4826 0)
			(end -0.2032 0)
			(stroke
				(width 0.2032)
				(type default)
			)
			(layer "F.SilkS")
		)
		(fp_rect
			(start -0.5842 1.3335)
			(end 0.5842 -1.3335)
			(stroke
				(width 0)
				(type default)
			)
			(fill no)
			(layer "F.CrtYd")
		)
		(fp_rect
			(start -0.5842 1.3335)
			(end 0.5842 -1.3335)
			(stroke
				(width 0)
				(type default)
			)
			(fill no)
			(layer "F.Fab")
		)
		(pad "1" smd custom
			(at 0 -0.762 180)
			(size 0.2159 0.2159)
			(layers "F.Cu" "F.Mask" "F.Paste")
			(net "HDD_PRSNT_NET12")
			(options
				(clearance outline)
				(anchor circle)
			)
			(primitives
				(gr_poly
					(pts
						(arc
							(start -0.3302 -0.4318)
							(mid -0.402042 -0.402042)
							(end -0.4318 -0.3302)
						)
						(arc
							(start -0.4318 0.3302)
							(mid -0.402042 0.402042)
							(end -0.3302 0.4318)
						)
						(arc
							(start 0.3302 0.4318)
							(mid 0.402042 0.402042)
							(end 0.4318 0.3302)
						)
						(arc
							(start 0.4318 -0.3302)
							(mid 0.402042 -0.402042)
							(end 0.3302 -0.4318)
						)
					)
					(width 0)
					(fill yes)
				)
			)
		)
		(pad "2" smd custom
			(at 0 0.762 180)
			(size 0.2159 0.2159)
			(layers "F.Cu" "F.Mask" "F.Paste")
			(net "HDD_PRSNT12")
			(options
				(clearance outline)
				(anchor circle)
			)
			(primitives
				(gr_poly
					(pts
						(arc
							(start -0.3302 -0.4318)
							(mid -0.402042 -0.402042)
							(end -0.4318 -0.3302)
						)
						(arc
							(start -0.4318 0.3302)
							(mid -0.402042 0.402042)
							(end -0.3302 0.4318)
						)
						(arc
							(start 0.3302 0.4318)
							(mid 0.402042 0.402042)
							(end 0.4318 0.3302)
						)
						(arc
							(start 0.4318 -0.3302)
							(mid 0.402042 -0.402042)
							(end 0.3302 -0.4318)
						)
					)
					(width 0)
					(fill yes)
				)
			)
		)
	)
	(footprint ""
		(layer "F.Cu")
		(at 81.914746 -12.474702 180)
		(property "Reference" "C333"
			(at 0 0 180)
			(layer "F.SilkS")
			(hide yes)
			(effects
				(font
					(size 1.27 1.27)
				)
			)
		)
		(property "Value" "SC10U25V6KX-1GP"
			(at -0.0762 -5.1308 180)
			(unlocked yes)
			(layer "F.Fab")
			(hide yes)
			(effects
				(font
					(size 1.016 1.016)
					(thickness 0.1524)
				)
			)
		)
		(property "Device Type" "C1206H71"
			(at -0.127 -6.6548 180)
			(unlocked yes)
			(layer "F.Fab")
			(hide yes)
			(effects
				(font
					(size 1.016 1.016)
					(thickness 0.1524)
				)
			)
		)
		(duplicate_pad_numbers_are_jumpers no)
		(fp_line
			(start 1.016 2.2352)
			(end -1.016 2.2352)
			(stroke
				(width 0.1524)
				(type default)
			)
			(layer "F.SilkS")
		)
		(fp_line
			(start 1.016 0.8382)
			(end 1.016 2.2352)
			(stroke
				(width 0.1524)
				(type default)
			)
			(layer "F.SilkS")
		)
		(fp_line
			(start 1.016 -2.2352)
			(end 1.016 -0.8382)
			(stroke
				(width 0.1524)
				(type default)
			)
			(layer "F.SilkS")
		)
		(fp_line
			(start -1.016 2.2352)
			(end -1.016 0.8382)
			(stroke
				(width 0.1524)
				(type default)
			)
			(layer "F.SilkS")
		)
		(fp_line
			(start -1.016 -0.8382)
			(end -1.016 -2.2352)
			(stroke
				(width 0.1524)
				(type default)
			)
			(layer "F.SilkS")
		)
		(fp_line
			(start -1.016 -2.2352)
			(end 1.016 -2.2352)
			(stroke
				(width 0.1524)
				(type default)
			)
			(layer "F.SilkS")
		)
		(fp_rect
			(start -1.0922 2.3114)
			(end 1.0922 -2.3114)
			(stroke
				(width 0)
				(type default)
			)
			(fill no)
			(layer "F.CrtYd")
		)
		(fp_poly
			(pts
				(xy 1.0922 -2.3114) (xy 1.0922 2.3114) (xy -1.0922 2.3114) (xy -1.0922 -2.3114)
			)
			(stroke
				(width 0)
				(type default)
			)
			(fill no)
			(layer "F.Fab")
		)
		(pad "1" smd rect
			(at 0 -1.397 180)
			(size 1.651 1.27)
			(layers "F.Cu" "F.Mask" "F.Paste")
			(net "P12V_HDD14")
		)
		(pad "2" smd rect
			(at 0 1.397 180)
			(size 1.651 1.27)
			(layers "F.Cu" "F.Mask" "F.Paste")
			(net "GND")
		)
	)
	(footprint ""
		(layer "F.Cu")
		(at 27.177746 -311.305702 180)
		(property "Reference" "R259"
			(at 0 0 180)
			(layer "F.SilkS")
			(hide yes)
			(effects
				(font
					(size 1.27 1.27)
				)
			)
		)
		(property "Value" "1KR2F-3-GP"
			(at 0.064008 -3.993896 180)
			(unlocked yes)
			(layer "F.Fab")
			(hide yes)
			(effects
				(font
					(size 1.016 1.016)
					(thickness 0.1524)
				)
			)
		)
		(property "Device Type" "R402H16"
			(at 0.064008 -5.517896 180)
			(unlocked yes)
			(layer "F.Fab")
			(hide yes)
			(effects
				(font
					(size 1.016 1.016)
					(thickness 0.1524)
				)
			)
		)
		(duplicate_pad_numbers_are_jumpers no)
		(fp_line
			(start 0.508 -0.9398)
			(end -0.508 -0.9398)
			(stroke
				(width 0.1524)
				(type default)
			)
			(layer "F.SilkS")
		)
		(fp_line
			(start -0.508 -0.9398)
			(end -0.508 0.9398)
			(stroke
				(width 0.1524)
				(type default)
			)
			(layer "F.SilkS")
		)
		(fp_rect
			(start -0.508 0.9398)
			(end 0.508 -0.9398)
			(stroke
				(width 0)
				(type default)
			)
			(fill no)
			(layer "F.CrtYd")
		)
		(fp_rect
			(start -0.508 0.9398)
			(end 0.508 -0.9398)
			(stroke
				(width 0)
				(type default)
			)
			(fill no)
			(layer "F.Fab")
		)
		(pad "1" smd custom
			(at 0 -0.4445 180)
			(size 0.1397 0.1397)
			(layers "F.Cu" "F.Mask" "F.Paste")
			(net "P3V3")
			(options
				(clearance outline)
				(anchor circle)
			)
			(primitives
				(gr_poly
					(pts
						(arc
							(start -0.1778 -0.2794)
							(mid -0.249642 -0.249642)
							(end -0.2794 -0.1778)
						)
						(arc
							(start -0.2794 0.1778)
							(mid -0.249642 0.249642)
							(end -0.1778 0.2794)
						)
						(arc
							(start 0.1778 0.2794)
							(mid 0.249642 0.249642)
							(end 0.2794 0.1778)
						)
						(arc
							(start 0.2794 -0.1778)
							(mid 0.249642 -0.249642)
							(end 0.1778 -0.2794)
						)
					)
					(width 0)
					(fill yes)
				)
			)
		)
		(pad "2" smd custom
			(at 0 0.4445 180)
			(size 0.1397 0.1397)
			(layers "F.Cu" "F.Mask" "F.Paste")
			(net "SW_PWR_HDD11")
			(options
				(clearance outline)
				(anchor circle)
			)
			(primitives
				(gr_poly
					(pts
						(arc
							(start -0.1778 -0.2794)
							(mid -0.249642 -0.249642)
							(end -0.2794 -0.1778)
						)
						(arc
							(start -0.2794 0.1778)
							(mid -0.249642 0.249642)
							(end -0.1778 0.2794)
						)
						(arc
							(start 0.1778 0.2794)
							(mid 0.249642 0.249642)
							(end 0.2794 0.1778)
						)
						(arc
							(start 0.2794 -0.1778)
							(mid 0.249642 -0.249642)
							(end 0.1778 -0.2794)
						)
					)
					(width 0)
					(fill yes)
				)
			)
		)
	)
	(footprint ""
		(layer "F.Cu")
		(at 199.897746 -286.6517)
		(property "Reference" "U7"
			(at 0 0 0)
			(layer "F.SilkS")
			(hide yes)
			(effects
				(font
					(size 1.27 1.27)
				)
			)
		)
		(property "Value" "74LVC1G08GW-1-GP"
			(at -2.3368 -8.6868 0)
			(unlocked yes)
			(layer "F.Fab")
			(hide yes)
			(effects
				(font
					(size 1.016 1.016)
					(thickness 0.1524)
				)
			)
		)
		(property "Device Type" "SC70-5H44"
			(at -2.3114 -10.414 0)
			(unlocked yes)
			(layer "F.Fab")
			(hide yes)
			(effects
				(font
					(size 1.016 1.016)
					(thickness 0.1524)
				)
			)
		)
		(duplicate_pad_numbers_are_jumpers no)
		(fp_line
			(start -1.27 -1.7018)
			(end 1.27 -1.7018)
			(stroke
				(width 0.1524)
				(type default)
			)
			(layer "F.SilkS")
		)
		(fp_line
			(start -1.27 1.7018)
			(end -1.27 -1.7018)
			(stroke
				(width 0.1524)
				(type default)
			)
			(layer "F.SilkS")
		)
		(fp_line
			(start 0.6604 -1.8034)
			(end 1.3843 -1.8034)
			(stroke
				(width 0.3302)
				(type default)
			)
			(layer "F.SilkS")
		)
		(fp_line
			(start 1.27 -1.7018)
			(end 1.27 1.7018)
			(stroke
				(width 0.1524)
				(type default)
			)
			(layer "F.SilkS")
		)
		(fp_line
			(start 1.27 1.7018)
			(end -1.27 1.7018)
			(stroke
				(width 0.1524)
				(type default)
			)
			(layer "F.SilkS")
		)
		(fp_line
			(start 1.3843 -1.8034)
			(end 1.3843 -1.1176)
			(stroke
				(width 0.3302)
				(type default)
			)
			(layer "F.SilkS")
		)
		(fp_rect
			(start -1.524 1.9558)
			(end 1.524 -1.9558)
			(stroke
				(width 0)
				(type default)
			)
			(fill no)
			(layer "F.CrtYd")
		)
		(fp_poly
			(pts
				(xy -1.524 -1.9558) (xy 1.524 -1.9558) (xy 1.524 1.9558) (xy -1.524 1.9558)
			)
			(stroke
				(width 0)
				(type default)
			)
			(fill no)
			(layer "F.Fab")
		)
		(pad "1" smd rect
			(at 0.65024 -0.8255)
			(size 0.4064 1.2192)
			(layers "F.Cu" "F.Mask" "F.Paste")
			(net "SAS2X28_B_HDD2_FLT")
		)
		(pad "2" smd rect
			(at 0 -0.8255)
			(size 0.4064 1.2192)
			(layers "F.Cu" "F.Mask" "F.Paste")
			(net "SAS2X28_A_HDD2_FLT")
		)
		(pad "3" smd rect
			(at -0.65024 -0.8255)
			(size 0.4064 1.2192)
			(layers "F.Cu" "F.Mask" "F.Paste")
			(net "GND")
		)
		(pad "4" smd rect
			(at -0.65024 0.8255)
			(size 0.4064 1.2192)
			(layers "F.Cu" "F.Mask" "F.Paste")
			(net "FLT_HDD2_DRIVE")
		)
		(pad "5" smd rect
			(at 0.65024 0.8255)
			(size 0.4064 1.2192)
			(layers "F.Cu" "F.Mask" "F.Paste")
			(net "P3V3")
		)
	)
	(footprint ""
		(layer "F.Cu")
		(at 194.691 -396.24 180)
		(property "Reference" "R564"
			(at 0 0 180)
			(layer "F.SilkS")
			(hide yes)
			(effects
				(font
					(size 1.27 1.27)
				)
			)
		)
		(property "Value" "300KR2F-GP"
			(at 0.064008 -3.993896 180)
			(unlocked yes)
			(layer "F.Fab")
			(hide yes)
			(effects
				(font
					(size 1.016 1.016)
					(thickness 0.1524)
				)
			)
		)
		(property "Device Type" "R402H16"
			(at 0.064008 -5.517896 180)
			(unlocked yes)
			(layer "F.Fab")
			(hide yes)
			(effects
				(font
					(size 1.016 1.016)
					(thickness 0.1524)
				)
			)
		)
		(duplicate_pad_numbers_are_jumpers no)
		(fp_line
			(start 0.508 -0.9398)
			(end -0.508 -0.9398)
			(stroke
				(width 0.1524)
				(type default)
			)
			(layer "F.SilkS")
		)
		(fp_line
			(start -0.508 -0.9398)
			(end -0.508 0.9398)
			(stroke
				(width 0.1524)
				(type default)
			)
			(layer "F.SilkS")
		)
		(fp_rect
			(start -0.508 0.9398)
			(end 0.508 -0.9398)
			(stroke
				(width 0)
				(type default)
			)
			(fill no)
			(layer "F.CrtYd")
		)
		(fp_rect
			(start -0.508 0.9398)
			(end 0.508 -0.9398)
			(stroke
				(width 0)
				(type default)
			)
			(fill no)
			(layer "F.Fab")
		)
		(pad "1" smd custom
			(at 0 -0.4445 180)
			(size 0.1397 0.1397)
			(layers "F.Cu" "F.Mask" "F.Paste")
			(net "SW_HDD1_N")
			(options
				(clearance outline)
				(anchor circle)
			)
			(primitives
				(gr_poly
					(pts
						(arc
							(start -0.1778 -0.2794)
							(mid -0.249642 -0.249642)
							(end -0.2794 -0.1778)
						)
						(arc
							(start -0.2794 0.1778)
							(mid -0.249642 0.249642)
							(end -0.1778 0.2794)
						)
						(arc
							(start 0.1778 0.2794)
							(mid 0.249642 0.249642)
							(end 0.2794 0.1778)
						)
						(arc
							(start 0.2794 -0.1778)
							(mid 0.249642 -0.249642)
							(end 0.1778 -0.2794)
						)
					)
					(width 0)
					(fill yes)
				)
			)
		)
		(pad "2" smd custom
			(at 0 0.4445 180)
			(size 0.1397 0.1397)
			(layers "F.Cu" "F.Mask" "F.Paste")
			(net "P12V")
			(options
				(clearance outline)
				(anchor circle)
			)
			(primitives
				(gr_poly
					(pts
						(arc
							(start -0.1778 -0.2794)
							(mid -0.249642 -0.249642)
							(end -0.2794 -0.1778)
						)
						(arc
							(start -0.2794 0.1778)
							(mid -0.249642 0.249642)
							(end -0.1778 0.2794)
						)
						(arc
							(start 0.1778 0.2794)
							(mid 0.249642 0.249642)
							(end 0.2794 0.1778)
						)
						(arc
							(start 0.2794 -0.1778)
							(mid 0.249642 -0.249642)
							(end 0.1778 -0.2794)
						)
					)
					(width 0)
					(fill yes)
				)
			)
		)
	)
)
